# T6G (Grand Teton) — schematic netlist excerpt (pin names and nets, part order shuffled) for the footprints in the layout excerpt that follows; sources: Cadence DE-HDL packaged netlist, KiCad conversion of 04192023_DAF0TMB3IC0_F0TG_MB_C_brd_V02_OCP.brd

PC76  Q_CAP  10UF 6.3V 20% X6S  pkg C0402  page 200 : A = PVDDCR_CPU1_P0_VCCS ; B = GND
C6640  Q_CAP_DIFFBUS  DIFF BUS_0.22UF 6.3V 20% X6S  pkg C0201  page 319 : \1\ = P5E_CPU1_P0_TX_BUF_C_DN<5> ; \2\ = P5E_CPU1_P0_TX_BUF_DN<5>
PC373_2  Q_CAP  0.1UF 25V 10% X7R  pkg 0402  page 218 : A = PVDDCR_CPU1_P1_VCCS ; B = GND

(kicad_pcb
	(version 20260206)
	(generator "pcbnew")
	(generator_version "10.0")
	(general
		(thickness 1.6)
		(legacy_teardrops no)
	)
	(paper "A4")
	(title_block
		(title "04192023_DAF0TMB3IC0_F0TG_MB_C_brd_V02_OCP.brd")
		(comment 1 "Grand Teton / footprints 1126-1128 of 8354")
	)
	(layers
		(0 "F.Cu" signal "TOP")
		(4 "In1.Cu" signal "GND")
		(6 "In2.Cu" signal "IN1")
		(8 "In3.Cu" signal "GND1")
		(10 "In4.Cu" signal "IN2")
		(12 "In5.Cu" signal "GND2")
		(14 "In6.Cu" signal "IN3")
		(16 "In7.Cu" signal "GND3")
		(18 "In8.Cu" signal "VCC")
		(20 "In9.Cu" signal "VCC1")
		(22 "In10.Cu" signal "GND4")
		(24 "In11.Cu" signal "IN4")
		(26 "In12.Cu" signal "GND5")
		(28 "In13.Cu" signal "IN5")
		(30 "In14.Cu" signal "GND6")
		(32 "In15.Cu" signal "IN6")
		(34 "In16.Cu" signal "GND7")
		(2 "B.Cu" signal "BOTTOM")
		(9 "F.Adhes" user "F.Adhesive")
		(11 "B.Adhes" user "B.Adhesive")
		(13 "F.Paste" user "Package Geometry/Pastemask Top")
		(15 "B.Paste" user "Package Geometry/Pastemask Bottom")
		(5 "F.SilkS" user "Ref Des/Silkscreen Top")
		(7 "B.SilkS" user "Ref Des/Silkscreen Bottom")
		(1 "F.Mask" user "Board Geometry/Soldermask Top")
		(3 "B.Mask" user "Board Geometry/Soldermask Bottom")
		(17 "Dwgs.User" user "User.Drawings")
		(19 "Cmts.User" user "User.Comments")
		(21 "Eco1.User" user "User.Eco1")
		(23 "Eco2.User" user "User.Eco2")
		(25 "Edge.Cuts" user "Board Geometry/Outline")
		(27 "Margin" user)
		(31 "F.CrtYd" user "Package Geometry/Place Bound Top")
		(29 "B.CrtYd" user "Package Geometry/Place Bound Bottom")
		(35 "F.Fab" user "Ref Des/Assembly Top")
		(33 "B.Fab" user "Ref Des/Assembly Bottom")
	)
	(footprint ""
		(layer "F.Cu")
		(at 316.23 -366.395 90)
		(property "Reference" "PC76"
			(at 0 0 90)
			(layer "F.SilkS")
			(hide yes)
			(effects
				(font
					(size 1.27 1.27)
				)
			)
		)
		(property "Value" ""
			(at 0 0 90)
			(layer "F.Fab")
			(effects
				(font
					(size 1.27 1.27)
				)
			)
		)
		(duplicate_pad_numbers_are_jumpers no)
		(fp_line
			(start 0.7874 -0.4064)
			(end 0.7874 0.4064)
			(stroke
				(width 0.1524)
				(type default)
			)
			(layer "F.SilkS")
		)
		(fp_line
			(start -0.7874 -0.4064)
			(end 0.7874 -0.4064)
			(stroke
				(width 0.1524)
				(type default)
			)
			(layer "F.SilkS")
		)
		(fp_line
			(start 0.7874 0.4064)
			(end -0.7874 0.4064)
			(stroke
				(width 0.1524)
				(type default)
			)
			(layer "F.SilkS")
		)
		(fp_line
			(start -0.7874 0.4064)
			(end -0.7874 -0.4064)
			(stroke
				(width 0.1524)
				(type default)
			)
			(layer "F.SilkS")
		)
		(fp_line
			(start -0.12065 -0.305054)
			(end -0.12065 -0.2794)
			(stroke
				(width 0.1)
				(type default)
			)
			(layer "F.Fab")
		)
		(fp_line
			(start -0.67945 -0.305054)
			(end -0.12065 -0.305054)
			(stroke
				(width 0.1)
				(type default)
			)
			(layer "F.Fab")
		)
		(fp_line
			(start 0.67945 -0.3048)
			(end 0.67945 0.3048)
			(stroke
				(width 0.1)
				(type default)
			)
			(layer "F.Fab")
		)
		(fp_line
			(start 0.12065 -0.3048)
			(end 0.67945 -0.3048)
			(stroke
				(width 0.1)
				(type default)
			)
			(layer "F.Fab")
		)
		(fp_line
			(start 0.12065 -0.2794)
			(end 0.12065 -0.3048)
			(stroke
				(width 0.1)
				(type default)
			)
			(layer "F.Fab")
		)
		(fp_line
			(start -0.12065 -0.2794)
			(end 0.12065 -0.2794)
			(stroke
				(width 0.1)
				(type default)
			)
			(layer "F.Fab")
		)
		(fp_line
			(start 0.120396 0.2794)
			(end -0.12065 0.2794)
			(stroke
				(width 0.1)
				(type default)
			)
			(layer "F.Fab")
		)
		(fp_line
			(start -0.12065 0.2794)
			(end -0.12065 0.3048)
			(stroke
				(width 0.1)
				(type default)
			)
			(layer "F.Fab")
		)
		(fp_line
			(start 0.67945 0.3048)
			(end 0.120396 0.3048)
			(stroke
				(width 0.1)
				(type default)
			)
			(layer "F.Fab")
		)
		(fp_line
			(start 0.120396 0.3048)
			(end 0.120396 0.2794)
			(stroke
				(width 0.1)
				(type default)
			)
			(layer "F.Fab")
		)
		(fp_line
			(start -0.12065 0.3048)
			(end -0.67945 0.3048)
			(stroke
				(width 0.1)
				(type default)
			)
			(layer "F.Fab")
		)
		(fp_line
			(start -0.67945 0.3048)
			(end -0.67945 -0.305054)
			(stroke
				(width 0.1)
				(type default)
			)
			(layer "F.Fab")
		)
		(pad "1" smd circle
			(at -0.40005 0 90)
			(size 0 0)
			(layers "F.Cu" "F.Mask" "F.Paste")
			(net "PVDDCR_CPU1_P0_VCCS")
		)
		(pad "2" smd circle
			(at 0.40005 0 90)
			(size 0 0)
			(layers "F.Cu" "F.Mask" "F.Paste")
			(net "GND")
		)
	)
	(footprint ""
		(layer "F.Cu")
		(at 76.070714 -339.850476 90)
		(property "Reference" "PC373_2"
			(at 0 0 90)
			(layer "F.SilkS")
			(hide yes)
			(effects
				(font
					(size 1.27 1.27)
				)
			)
		)
		(property "Value" ""
			(at 0 0 90)
			(layer "F.Fab")
			(effects
				(font
					(size 1.27 1.27)
				)
			)
		)
		(duplicate_pad_numbers_are_jumpers no)
		(fp_line
			(start 0.7874 -0.4064)
			(end 0.7874 0.4064)
			(stroke
				(width 0.1524)
				(type default)
			)
			(layer "F.SilkS")
		)
		(fp_line
			(start -0.7874 -0.4064)
			(end 0.7874 -0.4064)
			(stroke
				(width 0.1524)
				(type default)
			)
			(layer "F.SilkS")
		)
		(fp_line
			(start 0.7874 0.4064)
			(end -0.7874 0.4064)
			(stroke
				(width 0.1524)
				(type default)
			)
			(layer "F.SilkS")
		)
		(fp_line
			(start -0.7874 0.4064)
			(end -0.7874 -0.4064)
			(stroke
				(width 0.1524)
				(type default)
			)
			(layer "F.SilkS")
		)
		(fp_line
			(start -0.12065 -0.305054)
			(end -0.12065 -0.2794)
			(stroke
				(width 0.1)
				(type default)
			)
			(layer "F.Fab")
		)
		(fp_line
			(start -0.67945 -0.305054)
			(end -0.12065 -0.305054)
			(stroke
				(width 0.1)
				(type default)
			)
			(layer "F.Fab")
		)
		(fp_line
			(start 0.67945 -0.3048)
			(end 0.67945 0.3048)
			(stroke
				(width 0.1)
				(type default)
			)
			(layer "F.Fab")
		)
		(fp_line
			(start 0.12065 -0.3048)
			(end 0.67945 -0.3048)
			(stroke
				(width 0.1)
				(type default)
			)
			(layer "F.Fab")
		)
		(fp_line
			(start 0.12065 -0.2794)
			(end 0.12065 -0.3048)
			(stroke
				(width 0.1)
				(type default)
			)
			(layer "F.Fab")
		)
		(fp_line
			(start -0.12065 -0.2794)
			(end 0.12065 -0.2794)
			(stroke
				(width 0.1)
				(type default)
			)
			(layer "F.Fab")
		)
		(fp_line
			(start 0.120396 0.2794)
			(end -0.12065 0.2794)
			(stroke
				(width 0.1)
				(type default)
			)
			(layer "F.Fab")
		)
		(fp_line
			(start -0.12065 0.2794)
			(end -0.12065 0.3048)
			(stroke
				(width 0.1)
				(type default)
			)
			(layer "F.Fab")
		)
		(fp_line
			(start 0.67945 0.3048)
			(end 0.120396 0.3048)
			(stroke
				(width 0.1)
				(type default)
			)
			(layer "F.Fab")
		)
		(fp_line
			(start 0.120396 0.3048)
			(end 0.120396 0.2794)
			(stroke
				(width 0.1)
				(type default)
			)
			(layer "F.Fab")
		)
		(fp_line
			(start -0.12065 0.3048)
			(end -0.67945 0.3048)
			(stroke
				(width 0.1)
				(type default)
			)
			(layer "F.Fab")
		)
		(fp_line
			(start -0.67945 0.3048)
			(end -0.67945 -0.305054)
			(stroke
				(width 0.1)
				(type default)
			)
			(layer "F.Fab")
		)
		(pad "1" smd circle
			(at -0.40005 0 90)
			(size 0 0)
			(layers "F.Cu" "F.Mask" "F.Paste")
			(net "PVDDCR_CPU1_P1_VCCS")
		)
		(pad "2" smd circle
			(at 0.40005 0 90)
			(size 0 0)
			(layers "F.Cu" "F.Mask" "F.Paste")
			(net "GND")
		)
	)
	(footprint ""
		(layer "F.Cu")
		(at 63.084964 -408.517344 -90)
		(property "Reference" "C6640"
			(at 0 0 270)
			(layer "F.SilkS")
			(hide yes)
			(effects
				(font
					(size 1.27 1.27)
				)
			)
		)
		(property "Value" ""
			(at 0 0 270)
			(layer "F.Fab")
			(effects
				(font
					(size 1.27 1.27)
				)
			)
		)
		(duplicate_pad_numbers_are_jumpers no)
		(fp_line
			(start -0.299974 0.150114)
			(end -0.299974 -0.150114)
			(stroke
				(width 0.1)
				(type default)
			)
			(layer "F.Fab")
		)
		(fp_line
			(start 0.299974 0.150114)
			(end -0.299974 0.150114)
			(stroke
				(width 0.1)
				(type default)
			)
			(layer "F.Fab")
		)
		(fp_line
			(start -0.299974 -0.150114)
			(end 0.299974 -0.150114)
			(stroke
				(width 0.1)
				(type default)
			)
			(layer "F.Fab")
		)
		(fp_line
			(start 0.299974 -0.150114)
			(end 0.299974 0.150114)
			(stroke
				(width 0.1)
				(type default)
			)
			(layer "F.Fab")
		)
		(pad "1" smd rect
			(at -0.2667 0 270)
			(size 0.3048 0.381)
			(layers "F.Cu" "F.Mask" "F.Paste")
			(net "P5E_CPU1_P0_TX_BUF_C_DN<5>")
		)
		(pad "2" smd rect
			(at 0.2667 0 270)
			(size 0.3048 0.381)
			(layers "F.Cu" "F.Mask" "F.Paste")
			(net "P5E_CPU1_P0_TX_BUF_DN<5>")
		)
	)
)
